# S9S_MB_2U (Grand Teton) — schematic netlist excerpt (pin names and nets, part order shuffled) for the footprints in the layout excerpt that follows; sources: Cadence DE-HDL packaged netlist, KiCad conversion of 03242023_DA0F0TMBIJ0_F0T_Motherboard_J_brd_V01_OCP.brd

R4511  Q_RES  0 5% CHIP  pkg 0402LF  page 241 : A = SMB_HOST_3V3AUX_SDA ; B = SMB_HOST_3V3AUX_SDA_R4
R886  Q_RES  33.2 1% CHIP  pkg 0402LF  page 114 : A = PWRGD_CHE_CPU0_DIMM2 ; B = PWRGD_FAIL_CPU0_EF
C316  Q_CAP  47UF 4V 20% X6S  pkg C0805  page 78 : A = PVCCIN_CPU1 ; B = GND

(kicad_pcb
	(version 20260206)
	(generator "pcbnew")
	(generator_version "10.0")
	(general
		(thickness 1.6)
		(legacy_teardrops no)
	)
	(paper "A4")
	(title_block
		(title "03242023_DA0F0TMBIJ0_F0T_Motherboard_J_brd_V01_OCP.brd")
		(comment 1 "Grand Teton / footprints 5686-5688 of 6105")
	)
	(layers
		(0 "F.Cu" signal "TOP")
		(4 "In1.Cu" signal "GND")
		(6 "In2.Cu" signal "IN1")
		(8 "In3.Cu" signal "GND1")
		(10 "In4.Cu" signal "IN2")
		(12 "In5.Cu" signal "GND2")
		(14 "In6.Cu" signal "IN3")
		(16 "In7.Cu" signal "GND3")
		(18 "In8.Cu" signal "VCC")
		(20 "In9.Cu" signal "VCC1")
		(22 "In10.Cu" signal "GND4")
		(24 "In11.Cu" signal "IN4")
		(26 "In12.Cu" signal "GND5")
		(28 "In13.Cu" signal "IN5")
		(30 "In14.Cu" signal "GND6")
		(32 "In15.Cu" signal "IN6")
		(34 "In16.Cu" signal "GND7")
		(2 "B.Cu" signal "BOTTOM")
		(9 "F.Adhes" user "F.Adhesive")
		(11 "B.Adhes" user "B.Adhesive")
		(13 "F.Paste" user "Package Geometry/Pastemask Top")
		(15 "B.Paste" user "Package Geometry/Pastemask Bottom")
		(5 "F.SilkS" user "Ref Des/Silkscreen Top")
		(7 "B.SilkS" user "Ref Des/Silkscreen Bottom")
		(1 "F.Mask" user "Board Geometry/Soldermask Top")
		(3 "B.Mask" user "Board Geometry/Soldermask Bottom")
		(17 "Dwgs.User" user "User.Drawings")
		(19 "Cmts.User" user "User.Comments")
		(21 "Eco1.User" user "User.Eco1")
		(23 "Eco2.User" user "User.Eco2")
		(25 "Edge.Cuts" user "Board Geometry/Outline")
		(27 "Margin" user)
		(31 "F.CrtYd" user "Package Geometry/Place Bound Top")
		(29 "B.CrtYd" user "Package Geometry/Place Bound Bottom")
		(35 "F.Fab" user "Ref Des/Assembly Top")
		(33 "B.Fab" user "Ref Des/Assembly Bottom")
	)
	(footprint ""
		(layer "B.Cu")
		(at 105.679494 -244.82044 -90)
		(property "Reference" "C316"
			(at 0 0 90)
			(layer "B.SilkS")
			(hide yes)
			(effects
				(font
					(size 1.27 1.27)
				)
				(justify mirror)
			)
		)
		(property "Value" ""
			(at 0 0 90)
			(layer "B.Fab")
			(effects
				(font
					(size 1.27 1.27)
				)
				(justify mirror)
			)
		)
		(duplicate_pad_numbers_are_jumpers no)
		(fp_line
			(start -1.524 0.762)
			(end 1.524 0.762)
			(stroke
				(width 0.1524)
				(type default)
			)
			(layer "B.SilkS")
		)
		(fp_line
			(start 1.524 0.762)
			(end 1.524 -0.762)
			(stroke
				(width 0.1524)
				(type default)
			)
			(layer "B.SilkS")
		)
		(fp_line
			(start -1.524 -0.762)
			(end -1.524 0.762)
			(stroke
				(width 0.1524)
				(type default)
			)
			(layer "B.SilkS")
		)
		(fp_line
			(start 1.524 -0.762)
			(end -1.524 -0.762)
			(stroke
				(width 0.1524)
				(type default)
			)
			(layer "B.SilkS")
		)
		(fp_line
			(start -1.1049 0.724916)
			(end -1.1049 -0.724916)
			(stroke
				(width 0.1)
				(type default)
			)
			(layer "B.Fab")
		)
		(fp_line
			(start 1.1049 0.724916)
			(end -1.1049 0.724916)
			(stroke
				(width 0.1)
				(type default)
			)
			(layer "B.Fab")
		)
		(fp_line
			(start -1.1049 -0.724916)
			(end 1.1049 -0.724916)
			(stroke
				(width 0.1)
				(type default)
			)
			(layer "B.Fab")
		)
		(fp_line
			(start 1.1049 -0.724916)
			(end 1.1049 0.724916)
			(stroke
				(width 0.1)
				(type default)
			)
			(layer "B.Fab")
		)
		(pad "1" smd rect
			(at 0.889 0 270)
			(size 1.016 1.27)
			(layers "B.Cu" "B.Mask" "B.Paste")
			(net "PVCCIN_CPU1")
		)
		(pad "2" smd rect
			(at -0.889 0 270)
			(size 1.016 1.27)
			(layers "B.Cu" "B.Mask" "B.Paste")
			(net "GND")
		)
	)
	(footprint ""
		(layer "B.Cu")
		(at 179.85994 -21.364448 -90)
		(property "Reference" "R4511"
			(at 0 0 90)
			(layer "B.SilkS")
			(hide yes)
			(effects
				(font
					(size 1.27 1.27)
				)
				(justify mirror)
			)
		)
		(property "Value" ""
			(at 0 0 90)
			(layer "B.Fab")
			(effects
				(font
					(size 1.27 1.27)
				)
				(justify mirror)
			)
		)
		(duplicate_pad_numbers_are_jumpers no)
		(fp_line
			(start -0.7874 0.4064)
			(end 0.7874 0.4064)
			(stroke
				(width 0.1524)
				(type default)
			)
			(layer "B.SilkS")
		)
		(fp_line
			(start 0.7874 0.4064)
			(end 0.7874 -0.4064)
			(stroke
				(width 0.1524)
				(type default)
			)
			(layer "B.SilkS")
		)
		(fp_line
			(start -0.7874 -0.4064)
			(end -0.7874 0.4064)
			(stroke
				(width 0.1524)
				(type default)
			)
			(layer "B.SilkS")
		)
		(fp_line
			(start 0.7874 -0.4064)
			(end -0.7874 -0.4064)
			(stroke
				(width 0.1524)
				(type default)
			)
			(layer "B.SilkS")
		)
		(fp_line
			(start -0.67945 0.3048)
			(end -0.120396 0.3048)
			(stroke
				(width 0.1)
				(type default)
			)
			(layer "B.Fab")
		)
		(fp_line
			(start -0.120396 0.3048)
			(end -0.120396 0.2794)
			(stroke
				(width 0.1)
				(type default)
			)
			(layer "B.Fab")
		)
		(fp_line
			(start 0.12065 0.3048)
			(end 0.67945 0.3048)
			(stroke
				(width 0.1)
				(type default)
			)
			(layer "B.Fab")
		)
		(fp_line
			(start 0.67945 0.3048)
			(end 0.67945 -0.305054)
			(stroke
				(width 0.1)
				(type default)
			)
			(layer "B.Fab")
		)
		(fp_line
			(start -0.120396 0.2794)
			(end 0.12065 0.2794)
			(stroke
				(width 0.1)
				(type default)
			)
			(layer "B.Fab")
		)
		(fp_line
			(start 0.12065 0.2794)
			(end 0.12065 0.3048)
			(stroke
				(width 0.1)
				(type default)
			)
			(layer "B.Fab")
		)
		(fp_line
			(start -0.12065 -0.2794)
			(end -0.12065 -0.3048)
			(stroke
				(width 0.1)
				(type default)
			)
			(layer "B.Fab")
		)
		(fp_line
			(start 0.12065 -0.2794)
			(end -0.12065 -0.2794)
			(stroke
				(width 0.1)
				(type default)
			)
			(layer "B.Fab")
		)
		(fp_line
			(start -0.67945 -0.3048)
			(end -0.67945 0.3048)
			(stroke
				(width 0.1)
				(type default)
			)
			(layer "B.Fab")
		)
		(fp_line
			(start -0.12065 -0.3048)
			(end -0.67945 -0.3048)
			(stroke
				(width 0.1)
				(type default)
			)
			(layer "B.Fab")
		)
		(fp_line
			(start 0.12065 -0.305054)
			(end 0.12065 -0.2794)
			(stroke
				(width 0.1)
				(type default)
			)
			(layer "B.Fab")
		)
		(fp_line
			(start 0.67945 -0.305054)
			(end 0.12065 -0.305054)
			(stroke
				(width 0.1)
				(type default)
			)
			(layer "B.Fab")
		)
		(pad "1" smd circle
			(at 0.40005 0 90)
			(size 0 0)
			(layers "B.Cu" "B.Mask" "B.Paste")
			(net "SMB_HOST_3V3AUX_SDA")
		)
		(pad "2" smd circle
			(at -0.40005 0 90)
			(size 0 0)
			(layers "B.Cu" "B.Mask" "B.Paste")
			(net "SMB_HOST_3V3AUX_SDA_R4")
		)
	)
	(footprint ""
		(layer "B.Cu")
		(at 410.492956 -318.908176 90)
		(property "Reference" "R886"
			(at 0 0 90)
			(layer "B.SilkS")
			(hide yes)
			(effects
				(font
					(size 1.27 1.27)
				)
				(justify mirror)
			)
		)
		(property "Value" ""
			(at 0 0 90)
			(layer "B.Fab")
			(effects
				(font
					(size 1.27 1.27)
				)
				(justify mirror)
			)
		)
		(duplicate_pad_numbers_are_jumpers no)
		(fp_line
			(start 0.7874 -0.4064)
			(end -0.7874 -0.4064)
			(stroke
				(width 0.1524)
				(type default)
			)
			(layer "B.SilkS")
		)
		(fp_line
			(start -0.7874 -0.4064)
			(end -0.7874 0.4064)
			(stroke
				(width 0.1524)
				(type default)
			)
			(layer "B.SilkS")
		)
		(fp_line
			(start 0.7874 0.4064)
			(end 0.7874 -0.4064)
			(stroke
				(width 0.1524)
				(type default)
			)
			(layer "B.SilkS")
		)
		(fp_line
			(start -0.7874 0.4064)
			(end 0.7874 0.4064)
			(stroke
				(width 0.1524)
				(type default)
			)
			(layer "B.SilkS")
		)
		(fp_line
			(start 0.67945 -0.305054)
			(end 0.12065 -0.305054)
			(stroke
				(width 0.1)
				(type default)
			)
			(layer "B.Fab")
		)
		(fp_line
			(start 0.12065 -0.305054)
			(end 0.12065 -0.2794)
			(stroke
				(width 0.1)
				(type default)
			)
			(layer "B.Fab")
		)
		(fp_line
			(start -0.12065 -0.3048)
			(end -0.67945 -0.3048)
			(stroke
				(width 0.1)
				(type default)
			)
			(layer "B.Fab")
		)
		(fp_line
			(start -0.67945 -0.3048)
			(end -0.67945 0.3048)
			(stroke
				(width 0.1)
				(type default)
			)
			(layer "B.Fab")
		)
		(fp_line
			(start 0.12065 -0.2794)
			(end -0.12065 -0.2794)
			(stroke
				(width 0.1)
				(type default)
			)
			(layer "B.Fab")
		)
		(fp_line
			(start -0.12065 -0.2794)
			(end -0.12065 -0.3048)
			(stroke
				(width 0.1)
				(type default)
			)
			(layer "B.Fab")
		)
		(fp_line
			(start 0.12065 0.2794)
			(end 0.12065 0.3048)
			(stroke
				(width 0.1)
				(type default)
			)
			(layer "B.Fab")
		)
		(fp_line
			(start -0.120396 0.2794)
			(end 0.12065 0.2794)
			(stroke
				(width 0.1)
				(type default)
			)
			(layer "B.Fab")
		)
		(fp_line
			(start 0.67945 0.3048)
			(end 0.67945 -0.305054)
			(stroke
				(width 0.1)
				(type default)
			)
			(layer "B.Fab")
		)
		(fp_line
			(start 0.12065 0.3048)
			(end 0.67945 0.3048)
			(stroke
				(width 0.1)
				(type default)
			)
			(layer "B.Fab")
		)
		(fp_line
			(start -0.120396 0.3048)
			(end -0.120396 0.2794)
			(stroke
				(width 0.1)
				(type default)
			)
			(layer "B.Fab")
		)
		(fp_line
			(start -0.67945 0.3048)
			(end -0.120396 0.3048)
			(stroke
				(width 0.1)
				(type default)
			)
			(layer "B.Fab")
		)
		(pad "1" smd circle
			(at 0.40005 0 270)
			(size 0 0)
			(layers "B.Cu" "B.Mask" "B.Paste")
			(net "PWRGD_CHE_CPU0_DIMM2")
		)
		(pad "2" smd circle
			(at -0.40005 0 270)
			(size 0 0)
			(layers "B.Cu" "B.Mask" "B.Paste")
			(net "PWRGD_FAIL_CPU0_EF")
		)
	)
)
